(kicad_pcb
	(version 20260206)
	(generator "pcbnew")
	(generator_version "10.0")
	(general
		(thickness 1.6)
		(legacy_teardrops no)
	)
	(paper "A4")
	(title_block
		(title "03242023_DA0F0TMBIJ0_F0T_Motherboard_J_brd_V01_OCP.brd")
		(comment 1 "Grand Teton / footprints 2694-2699 of 6105")
	)
	(layers
		(0 "F.Cu" signal "TOP")
		(4 "In1.Cu" signal "GND")
		(6 "In2.Cu" signal "IN1")
		(8 "In3.Cu" signal "GND1")
		(10 "In4.Cu" signal "IN2")
		(12 "In5.Cu" signal "GND2")
		(14 "In6.Cu" signal "IN3")
		(16 "In7.Cu" signal "GND3")
		(18 "In8.Cu" signal "VCC")
		(20 "In9.Cu" signal "VCC1")
		(22 "In10.Cu" signal "GND4")
		(24 "In11.Cu" signal "IN4")
		(26 "In12.Cu" signal "GND5")
		(28 "In13.Cu" signal "IN5")
		(30 "In14.Cu" signal "GND6")
		(32 "In15.Cu" signal "IN6")
		(34 "In16.Cu" signal "GND7")
		(2 "B.Cu" signal "BOTTOM")
		(9 "F.Adhes" user "F.Adhesive")
		(11 "B.Adhes" user "B.Adhesive")
		(13 "F.Paste" user "Package Geometry/Pastemask Top")
		(15 "B.Paste" user "Package Geometry/Pastemask Bottom")
		(5 "F.SilkS" user "Ref Des/Silkscreen Top")
		(7 "B.SilkS" user "Ref Des/Silkscreen Bottom")
		(1 "F.Mask" user "Board Geometry/Soldermask Top")
		(3 "B.Mask" user "Board Geometry/Soldermask Bottom")
		(17 "Dwgs.User" user "User.Drawings")
		(19 "Cmts.User" user "User.Comments")
		(21 "Eco1.User" user "User.Eco1")
		(23 "Eco2.User" user "User.Eco2")
		(25 "Edge.Cuts" user "Board Geometry/Outline")
		(27 "Margin" user)
		(31 "F.CrtYd" user "Package Geometry/Place Bound Top")
		(29 "B.CrtYd" user "Package Geometry/Place Bound Bottom")
		(35 "F.Fab" user "Ref Des/Assembly Top")
		(33 "B.Fab" user "Ref Des/Assembly Bottom")
	)
	(footprint ""
		(layer "F.Cu")
		(at 28.853638 -125.194314 -90)
		(property "Reference" "PC1193"
			(at 0 0 270)
			(layer "F.SilkS")
			(hide yes)
			(effects
				(font
					(size 1.27 1.27)
				)
			)
		)
		(property "Value" ""
			(at 0 0 270)
			(layer "F.Fab")
			(effects
				(font
					(size 1.27 1.27)
				)
			)
		)
		(duplicate_pad_numbers_are_jumpers no)
		(fp_line
			(start -0.7874 0.4064)
			(end -0.7874 -0.4064)
			(stroke
				(width 0.1524)
				(type default)
			)
			(layer "F.SilkS")
		)
		(fp_line
			(start 0.7874 0.4064)
			(end -0.7874 0.4064)
			(stroke
				(width 0.1524)
				(type default)
			)
			(layer "F.SilkS")
		)
		(fp_line
			(start -0.7874 -0.4064)
			(end 0.7874 -0.4064)
			(stroke
				(width 0.1524)
				(type default)
			)
			(layer "F.SilkS")
		)
		(fp_line
			(start 0.7874 -0.4064)
			(end 0.7874 0.4064)
			(stroke
				(width 0.1524)
				(type default)
			)
			(layer "F.SilkS")
		)
		(fp_line
			(start -0.67945 0.3048)
			(end -0.67945 -0.305054)
			(stroke
				(width 0.1)
				(type default)
			)
			(layer "F.Fab")
		)
		(fp_line
			(start -0.12065 0.3048)
			(end -0.67945 0.3048)
			(stroke
				(width 0.1)
				(type default)
			)
			(layer "F.Fab")
		)
		(fp_line
			(start 0.120396 0.3048)
			(end 0.120396 0.2794)
			(stroke
				(width 0.1)
				(type default)
			)
			(layer "F.Fab")
		)
		(fp_line
			(start 0.67945 0.3048)
			(end 0.120396 0.3048)
			(stroke
				(width 0.1)
				(type default)
			)
			(layer "F.Fab")
		)
		(fp_line
			(start -0.12065 0.2794)
			(end -0.12065 0.3048)
			(stroke
				(width 0.1)
				(type default)
			)
			(layer "F.Fab")
		)
		(fp_line
			(start 0.120396 0.2794)
			(end -0.12065 0.2794)
			(stroke
				(width 0.1)
				(type default)
			)
			(layer "F.Fab")
		)
		(fp_line
			(start -0.12065 -0.2794)
			(end 0.12065 -0.2794)
			(stroke
				(width 0.1)
				(type default)
			)
			(layer "F.Fab")
		)
		(fp_line
			(start 0.12065 -0.2794)
			(end 0.12065 -0.3048)
			(stroke
				(width 0.1)
				(type default)
			)
			(layer "F.Fab")
		)
		(fp_line
			(start 0.12065 -0.3048)
			(end 0.67945 -0.3048)
			(stroke
				(width 0.1)
				(type default)
			)
			(layer "F.Fab")
		)
		(fp_line
			(start 0.67945 -0.3048)
			(end 0.67945 0.3048)
			(stroke
				(width 0.1)
				(type default)
			)
			(layer "F.Fab")
		)
		(fp_line
			(start -0.67945 -0.305054)
			(end -0.12065 -0.305054)
			(stroke
				(width 0.1)
				(type default)
			)
			(layer "F.Fab")
		)
		(fp_line
			(start -0.12065 -0.305054)
			(end -0.12065 -0.2794)
			(stroke
				(width 0.1)
				(type default)
			)
			(layer "F.Fab")
		)
		(pad "1" smd circle
			(at -0.40005 0 270)
			(size 0 0)
			(layers "F.Cu" "F.Mask" "F.Paste")
			(net "PVCCINFAON_CPU1_VREF")
		)
		(pad "2" smd circle
			(at 0.40005 0 270)
			(size 0 0)
			(layers "F.Cu" "F.Mask" "F.Paste")
			(net "GND")
		)
	)
	(footprint ""
		(layer "F.Cu")
		(at 251.74956 -108.192824 90)
		(property "Reference" "R1011"
			(at 0 0 90)
			(layer "F.SilkS")
			(hide yes)
			(effects
				(font
					(size 1.27 1.27)
				)
			)
		)
		(property "Value" ""
			(at 0 0 90)
			(layer "F.Fab")
			(effects
				(font
					(size 1.27 1.27)
				)
			)
		)
		(duplicate_pad_numbers_are_jumpers no)
		(fp_line
			(start 0.7874 -0.4064)
			(end 0.7874 0.4064)
			(stroke
				(width 0.1524)
				(type default)
			)
			(layer "F.SilkS")
		)
		(fp_line
			(start -0.7874 -0.4064)
			(end 0.7874 -0.4064)
			(stroke
				(width 0.1524)
				(type default)
			)
			(layer "F.SilkS")
		)
		(fp_line
			(start 0.7874 0.4064)
			(end -0.7874 0.4064)
			(stroke
				(width 0.1524)
				(type default)
			)
			(layer "F.SilkS")
		)
		(fp_line
			(start -0.7874 0.4064)
			(end -0.7874 -0.4064)
			(stroke
				(width 0.1524)
				(type default)
			)
			(layer "F.SilkS")
		)
		(fp_line
			(start -0.12065 -0.305054)
			(end -0.12065 -0.2794)
			(stroke
				(width 0.1)
				(type default)
			)
			(layer "F.Fab")
		)
		(fp_line
			(start -0.67945 -0.305054)
			(end -0.12065 -0.305054)
			(stroke
				(width 0.1)
				(type default)
			)
			(layer "F.Fab")
		)
		(fp_line
			(start 0.67945 -0.3048)
			(end 0.67945 0.3048)
			(stroke
				(width 0.1)
				(type default)
			)
			(layer "F.Fab")
		)
		(fp_line
			(start 0.12065 -0.3048)
			(end 0.67945 -0.3048)
			(stroke
				(width 0.1)
				(type default)
			)
			(layer "F.Fab")
		)
		(fp_line
			(start 0.12065 -0.2794)
			(end 0.12065 -0.3048)
			(stroke
				(width 0.1)
				(type default)
			)
			(layer "F.Fab")
		)
		(fp_line
			(start -0.12065 -0.2794)
			(end 0.12065 -0.2794)
			(stroke
				(width 0.1)
				(type default)
			)
			(layer "F.Fab")
		)
		(fp_line
			(start 0.120396 0.2794)
			(end -0.12065 0.2794)
			(stroke
				(width 0.1)
				(type default)
			)
			(layer "F.Fab")
		)
		(fp_line
			(start -0.12065 0.2794)
			(end -0.12065 0.3048)
			(stroke
				(width 0.1)
				(type default)
			)
			(layer "F.Fab")
		)
		(fp_line
			(start 0.67945 0.3048)
			(end 0.120396 0.3048)
			(stroke
				(width 0.1)
				(type default)
			)
			(layer "F.Fab")
		)
		(fp_line
			(start 0.120396 0.3048)
			(end 0.120396 0.2794)
			(stroke
				(width 0.1)
				(type default)
			)
			(layer "F.Fab")
		)
		(fp_line
			(start -0.12065 0.3048)
			(end -0.67945 0.3048)
			(stroke
				(width 0.1)
				(type default)
			)
			(layer "F.Fab")
		)
		(fp_line
			(start -0.67945 0.3048)
			(end -0.67945 -0.305054)
			(stroke
				(width 0.1)
				(type default)
			)
			(layer "F.Fab")
		)
		(pad "1" smd circle
			(at -0.40005 0 90)
			(size 0 0)
			(layers "F.Cu" "F.Mask" "F.Paste")
			(net "CLK_25M_CK440_ISCLK_REF_DN")
		)
		(pad "2" smd circle
			(at 0.40005 0 90)
			(size 0 0)
			(layers "F.Cu" "F.Mask" "F.Paste")
			(net "CLK_25M_PCH_REF_NS_DN")
		)
	)
	(footprint ""
		(layer "F.Cu")
		(at 428.226474 -125.80366)
		(property "Reference" "PR357"
			(at 0 0 0)
			(layer "F.SilkS")
			(hide yes)
			(effects
				(font
					(size 1.27 1.27)
				)
			)
		)
		(property "Value" ""
			(at 0 0 0)
			(layer "F.Fab")
			(effects
				(font
					(size 1.27 1.27)
				)
			)
		)
		(duplicate_pad_numbers_are_jumpers no)
		(fp_line
			(start -0.7874 -0.4064)
			(end 0.7874 -0.4064)
			(stroke
				(width 0.1524)
				(type default)
			)
			(layer "F.SilkS")
		)
		(fp_line
			(start -0.7874 0.4064)
			(end -0.7874 -0.4064)
			(stroke
				(width 0.1524)
				(type default)
			)
			(layer "F.SilkS")
		)
		(fp_line
			(start 0.7874 -0.4064)
			(end 0.7874 0.4064)
			(stroke
				(width 0.1524)
				(type default)
			)
			(layer "F.SilkS")
		)
		(fp_line
			(start 0.7874 0.4064)
			(end -0.7874 0.4064)
			(stroke
				(width 0.1524)
				(type default)
			)
			(layer "F.SilkS")
		)
		(fp_line
			(start -0.67945 -0.305054)
			(end -0.12065 -0.305054)
			(stroke
				(width 0.1)
				(type default)
			)
			(layer "F.Fab")
		)
		(fp_line
			(start -0.67945 0.3048)
			(end -0.67945 -0.305054)
			(stroke
				(width 0.1)
				(type default)
			)
			(layer "F.Fab")
		)
		(fp_line
			(start -0.12065 -0.305054)
			(end -0.12065 -0.2794)
			(stroke
				(width 0.1)
				(type default)
			)
			(layer "F.Fab")
		)
		(fp_line
			(start -0.12065 -0.2794)
			(end 0.12065 -0.2794)
			(stroke
				(width 0.1)
				(type default)
			)
			(layer "F.Fab")
		)
		(fp_line
			(start -0.12065 0.2794)
			(end -0.12065 0.3048)
			(stroke
				(width 0.1)
				(type default)
			)
			(layer "F.Fab")
		)
		(fp_line
			(start -0.12065 0.3048)
			(end -0.67945 0.3048)
			(stroke
				(width 0.1)
				(type default)
			)
			(layer "F.Fab")
		)
		(fp_line
			(start 0.120396 0.2794)
			(end -0.12065 0.2794)
			(stroke
				(width 0.1)
				(type default)
			)
			(layer "F.Fab")
		)
		(fp_line
			(start 0.120396 0.3048)
			(end 0.120396 0.2794)
			(stroke
				(width 0.1)
				(type default)
			)
			(layer "F.Fab")
		)
		(fp_line
			(start 0.12065 -0.3048)
			(end 0.67945 -0.3048)
			(stroke
				(width 0.1)
				(type default)
			)
			(layer "F.Fab")
		)
		(fp_line
			(start 0.12065 -0.2794)
			(end 0.12065 -0.3048)
			(stroke
				(width 0.1)
				(type default)
			)
			(layer "F.Fab")
		)
		(fp_line
			(start 0.67945 -0.3048)
			(end 0.67945 0.3048)
			(stroke
				(width 0.1)
				(type default)
			)
			(layer "F.Fab")
		)
		(fp_line
			(start 0.67945 0.3048)
			(end 0.120396 0.3048)
			(stroke
				(width 0.1)
				(type default)
			)
			(layer "F.Fab")
		)
		(pad "1" smd circle
			(at -0.40005 0)
			(size 0 0)
			(layers "F.Cu" "F.Mask" "F.Paste")
			(net "PVCCD_HV_CPU0_VREF")
		)
		(pad "2" smd circle
			(at 0.40005 0)
			(size 0 0)
			(layers "F.Cu" "F.Mask" "F.Paste")
			(net "PVCCD_HV_CPU0_ADDR")
		)
	)
	(footprint ""
		(layer "F.Cu")
		(at 136.508998 -348.061026)
		(property "Reference" "PR285"
			(at 0 0 0)
			(layer "F.SilkS")
			(hide yes)
			(effects
				(font
					(size 1.27 1.27)
				)
			)
		)
		(property "Value" ""
			(at 0 0 0)
			(layer "F.Fab")
			(effects
				(font
					(size 1.27 1.27)
				)
			)
		)
		(duplicate_pad_numbers_are_jumpers no)
		(fp_line
			(start -0.7874 -0.4064)
			(end 0.7874 -0.4064)
			(stroke
				(width 0.1524)
				(type default)
			)
			(layer "F.SilkS")
		)
		(fp_line
			(start -0.7874 0.4064)
			(end -0.7874 -0.4064)
			(stroke
				(width 0.1524)
				(type default)
			)
			(layer "F.SilkS")
		)
		(fp_line
			(start 0.7874 -0.4064)
			(end 0.7874 0.4064)
			(stroke
				(width 0.1524)
				(type default)
			)
			(layer "F.SilkS")
		)
		(fp_line
			(start 0.7874 0.4064)
			(end -0.7874 0.4064)
			(stroke
				(width 0.1524)
				(type default)
			)
			(layer "F.SilkS")
		)
		(fp_line
			(start -0.67945 -0.305054)
			(end -0.12065 -0.305054)
			(stroke
				(width 0.1)
				(type default)
			)
			(layer "F.Fab")
		)
		(fp_line
			(start -0.67945 0.3048)
			(end -0.67945 -0.305054)
			(stroke
				(width 0.1)
				(type default)
			)
			(layer "F.Fab")
		)
		(fp_line
			(start -0.12065 -0.305054)
			(end -0.12065 -0.2794)
			(stroke
				(width 0.1)
				(type default)
			)
			(layer "F.Fab")
		)
		(fp_line
			(start -0.12065 -0.2794)
			(end 0.12065 -0.2794)
			(stroke
				(width 0.1)
				(type default)
			)
			(layer "F.Fab")
		)
		(fp_line
			(start -0.12065 0.2794)
			(end -0.12065 0.3048)
			(stroke
				(width 0.1)
				(type default)
			)
			(layer "F.Fab")
		)
		(fp_line
			(start -0.12065 0.3048)
			(end -0.67945 0.3048)
			(stroke
				(width 0.1)
				(type default)
			)
			(layer "F.Fab")
		)
		(fp_line
			(start 0.120396 0.2794)
			(end -0.12065 0.2794)
			(stroke
				(width 0.1)
				(type default)
			)
			(layer "F.Fab")
		)
		(fp_line
			(start 0.120396 0.3048)
			(end 0.120396 0.2794)
			(stroke
				(width 0.1)
				(type default)
			)
			(layer "F.Fab")
		)
		(fp_line
			(start 0.12065 -0.3048)
			(end 0.67945 -0.3048)
			(stroke
				(width 0.1)
				(type default)
			)
			(layer "F.Fab")
		)
		(fp_line
			(start 0.12065 -0.2794)
			(end 0.12065 -0.3048)
			(stroke
				(width 0.1)
				(type default)
			)
			(layer "F.Fab")
		)
		(fp_line
			(start 0.67945 -0.3048)
			(end 0.67945 0.3048)
			(stroke
				(width 0.1)
				(type default)
			)
			(layer "F.Fab")
		)
		(fp_line
			(start 0.67945 0.3048)
			(end 0.120396 0.3048)
			(stroke
				(width 0.1)
				(type default)
			)
			(layer "F.Fab")
		)
		(pad "1" smd circle
			(at -0.40005 0)
			(size 0 0)
			(layers "F.Cu" "F.Mask" "F.Paste")
			(net "PVCCIN_CPU1_LSET8")
		)
		(pad "2" smd circle
			(at 0.40005 0)
			(size 0 0)
			(layers "F.Cu" "F.Mask" "F.Paste")
			(net "GND")
		)
	)
	(footprint ""
		(layer "F.Cu")
		(at 160.83788 -115.026948)
		(property "Reference" "R3483"
			(at 0 0 0)
			(layer "F.SilkS")
			(hide yes)
			(effects
				(font
					(size 1.27 1.27)
				)
			)
		)
		(property "Value" ""
			(at 0 0 0)
			(layer "F.Fab")
			(effects
				(font
					(size 1.27 1.27)
				)
			)
		)
		(duplicate_pad_numbers_are_jumpers no)
		(fp_line
			(start -0.7874 -0.4064)
			(end 0.7874 -0.4064)
			(stroke
				(width 0.1524)
				(type default)
			)
			(layer "F.SilkS")
		)
		(fp_line
			(start -0.7874 0.4064)
			(end -0.7874 -0.4064)
			(stroke
				(width 0.1524)
				(type default)
			)
			(layer "F.SilkS")
		)
		(fp_line
			(start 0.7874 -0.4064)
			(end 0.7874 0.4064)
			(stroke
				(width 0.1524)
				(type default)
			)
			(layer "F.SilkS")
		)
		(fp_line
			(start 0.7874 0.4064)
			(end -0.7874 0.4064)
			(stroke
				(width 0.1524)
				(type default)
			)
			(layer "F.SilkS")
		)
		(fp_line
			(start -0.67945 -0.305054)
			(end -0.12065 -0.305054)
			(stroke
				(width 0.1)
				(type default)
			)
			(layer "F.Fab")
		)
		(fp_line
			(start -0.67945 0.3048)
			(end -0.67945 -0.305054)
			(stroke
				(width 0.1)
				(type default)
			)
			(layer "F.Fab")
		)
		(fp_line
			(start -0.12065 -0.305054)
			(end -0.12065 -0.2794)
			(stroke
				(width 0.1)
				(type default)
			)
			(layer "F.Fab")
		)
		(fp_line
			(start -0.12065 -0.2794)
			(end 0.12065 -0.2794)
			(stroke
				(width 0.1)
				(type default)
			)
			(layer "F.Fab")
		)
		(fp_line
			(start -0.12065 0.2794)
			(end -0.12065 0.3048)
			(stroke
				(width 0.1)
				(type default)
			)
			(layer "F.Fab")
		)
		(fp_line
			(start -0.12065 0.3048)
			(end -0.67945 0.3048)
			(stroke
				(width 0.1)
				(type default)
			)
			(layer "F.Fab")
		)
		(fp_line
			(start 0.120396 0.2794)
			(end -0.12065 0.2794)
			(stroke
				(width 0.1)
				(type default)
			)
			(layer "F.Fab")
		)
		(fp_line
			(start 0.120396 0.3048)
			(end 0.120396 0.2794)
			(stroke
				(width 0.1)
				(type default)
			)
			(layer "F.Fab")
		)
		(fp_line
			(start 0.12065 -0.3048)
			(end 0.67945 -0.3048)
			(stroke
				(width 0.1)
				(type default)
			)
			(layer "F.Fab")
		)
		(fp_line
			(start 0.12065 -0.2794)
			(end 0.12065 -0.3048)
			(stroke
				(width 0.1)
				(type default)
			)
			(layer "F.Fab")
		)
		(fp_line
			(start 0.67945 -0.3048)
			(end 0.67945 0.3048)
			(stroke
				(width 0.1)
				(type default)
			)
			(layer "F.Fab")
		)
		(fp_line
			(start 0.67945 0.3048)
			(end 0.120396 0.3048)
			(stroke
				(width 0.1)
				(type default)
			)
			(layer "F.Fab")
		)
		(pad "1" smd circle
			(at -0.40005 0)
			(size 0 0)
			(layers "F.Cu" "F.Mask" "F.Paste")
			(net "GPU_FPGA_EROT_RECOV_N")
		)
		(pad "2" smd circle
			(at 0.40005 0)
			(size 0 0)
			(layers "F.Cu" "F.Mask" "F.Paste")
			(net "GPU_FPGA_EROT_RECOV_R_N")
		)
	)
	(footprint ""
		(layer "F.Cu")
		(at 146.959828 -92.622878 -90)
		(property "Reference" "R4394"
			(at 0 0 270)
			(layer "F.SilkS")
			(hide yes)
			(effects
				(font
					(size 1.27 1.27)
				)
			)
		)
		(property "Value" ""
			(at 0 0 270)
			(layer "F.Fab")
			(effects
				(font
					(size 1.27 1.27)
				)
			)
		)
		(duplicate_pad_numbers_are_jumpers no)
		(fp_line
			(start -0.7874 0.4064)
			(end -0.7874 -0.4064)
			(stroke
				(width 0.1524)
				(type default)
			)
			(layer "F.SilkS")
		)
		(fp_line
			(start 0.7874 0.4064)
			(end -0.7874 0.4064)
			(stroke
				(width 0.1524)
				(type default)
			)
			(layer "F.SilkS")
		)
		(fp_line
			(start -0.7874 -0.4064)
			(end 0.7874 -0.4064)
			(stroke
				(width 0.1524)
				(type default)
			)
			(layer "F.SilkS")
		)
		(fp_line
			(start 0.7874 -0.4064)
			(end 0.7874 0.4064)
			(stroke
				(width 0.1524)
				(type default)
			)
			(layer "F.SilkS")
		)
		(fp_line
			(start -0.67945 0.3048)
			(end -0.67945 -0.305054)
			(stroke
				(width 0.1)
				(type default)
			)
			(layer "F.Fab")
		)
		(fp_line
			(start -0.12065 0.3048)
			(end -0.67945 0.3048)
			(stroke
				(width 0.1)
				(type default)
			)
			(layer "F.Fab")
		)
		(fp_line
			(start 0.120396 0.3048)
			(end 0.120396 0.2794)
			(stroke
				(width 0.1)
				(type default)
			)
			(layer "F.Fab")
		)
		(fp_line
			(start 0.67945 0.3048)
			(end 0.120396 0.3048)
			(stroke
				(width 0.1)
				(type default)
			)
			(layer "F.Fab")
		)
		(fp_line
			(start -0.12065 0.2794)
			(end -0.12065 0.3048)
			(stroke
				(width 0.1)
				(type default)
			)
			(layer "F.Fab")
		)
		(fp_line
			(start 0.120396 0.2794)
			(end -0.12065 0.2794)
			(stroke
				(width 0.1)
				(type default)
			)
			(layer "F.Fab")
		)
		(fp_line
			(start -0.12065 -0.2794)
			(end 0.12065 -0.2794)
			(stroke
				(width 0.1)
				(type default)
			)
			(layer "F.Fab")
		)
		(fp_line
			(start 0.12065 -0.2794)
			(end 0.12065 -0.3048)
			(stroke
				(width 0.1)
				(type default)
			)
			(layer "F.Fab")
		)
		(fp_line
			(start 0.12065 -0.3048)
			(end 0.67945 -0.3048)
			(stroke
				(width 0.1)
				(type default)
			)
			(layer "F.Fab")
		)
		(fp_line
			(start 0.67945 -0.3048)
			(end 0.67945 0.3048)
			(stroke
				(width 0.1)
				(type default)
			)
			(layer "F.Fab")
		)
		(fp_line
			(start -0.67945 -0.305054)
			(end -0.12065 -0.305054)
			(stroke
				(width 0.1)
				(type default)
			)
			(layer "F.Fab")
		)
		(fp_line
			(start -0.12065 -0.305054)
			(end -0.12065 -0.2794)
			(stroke
				(width 0.1)
				(type default)
			)
			(layer "F.Fab")
		)
		(pad "1" smd circle
			(at -0.40005 0 270)
			(size 0 0)
			(layers "F.Cu" "F.Mask" "F.Paste")
			(net "H_CPU_ERR2_LVC2_R_N")
		)
		(pad "2" smd circle
			(at 0.40005 0 270)
			(size 0 0)
			(layers "F.Cu" "F.Mask" "F.Paste")
			(net "H_CPU_ERR2_PCH_R_N")
		)
	)
)
